# S9S_MB_2U (Grand Teton) — schematic parts with pin connectivity, parts 1599–1599 of 6093; source: Cadence DE-HDL packaged netlist (pstxprt.dat, pstxnet.dat, pstchip.dat)

J6  SCONN288_ADR50017P087CC  SCONN288_ADR50017-P087CC IO  pkg DDR288S_1-1VXB  page 87
  1  VIN_BULK0  POWER  = P12V_S3_AUX_CPU0_NVDIMM
  2  RFU0  TRI  = TP_CHC_CPU0_DIMM2_FRU_0
  3  VIN_MGMT  POWER  = P3V3_AUX
  4  HSCL  IN  = I3C_SPD_DDRABCD_CPU0_LVC1_SCL_5
  5  HSDA  BI  = I3C_SPD_DDRABCD_CPU0_LVC1_SDA
  6  VSS0  POWER  = GND
  7  DQ0_A  BI  = M_C_CPU0_SA_DQ<0>
  8  VSS1  POWER  = GND
  9  DQ1_A  BI  = M_C_CPU0_SA_DQ<1>
  10  VSS2  POWER  = GND
  11  DQS0_A_T  BI  = M_C_CPU0_SA_DQS_DP<0>
  12  DQS0_A_C  BI  = M_C_CPU0_SA_DQS_DN<0>
  13  VSS3  POWER  = GND
  14  DQ4_A  BI  = M_C_CPU0_SA_DQ<4>
  15  VSS4  POWER  = GND
  16  DQ5_A  BI  = M_C_CPU0_SA_DQ<5>
  17  VSS5  POWER  = GND
  18  DQ8_A  BI  = M_C_CPU0_SA_DQ<8>
  19  VSS6  POWER  = GND
  20  DQ9_A  BI  = M_C_CPU0_SA_DQ<9>
  21  VSS7  POWER  = GND
  22  DQS1_A_T  BI  = M_C_CPU0_SA_DQS_DP<1>
  23  DQS1_A_C  BI  = M_C_CPU0_SA_DQS_DN<1>
  24  VSS8  POWER  = GND
  25  DQ12_A  BI  = M_C_CPU0_SA_DQ<12>
  26  VSS9  POWER  = GND
  27  DQ13_A  BI  = M_C_CPU0_SA_DQ<13>
  28  VSS10  POWER  = GND
  29  DQ16_A  BI  = M_C_CPU0_SA_DQ<16>
  30  VSS11  POWER  = GND
  31  DQ17_A  BI  = M_C_CPU0_SA_DQ<17>
  32  VSS12  POWER  = GND
  33  DQS2_A_T  BI  = M_C_CPU0_SA_DQS_DP<2>
  34  DQS2_A_C  BI  = M_C_CPU0_SA_DQS_DN<2>
  35  VSS13  POWER  = GND
  36  DQ20_A  BI  = M_C_CPU0_SA_DQ<20>
  37  VSS14  POWER  = GND
  38  DQ21_A  BI  = M_C_CPU0_SA_DQ<21>
  39  VSS15  POWER  = GND
  40  DQ24_A  BI  = M_C_CPU0_SA_DQ<24>
  41  VSS16  POWER  = GND
  42  DQ25_A  BI  = M_C_CPU0_SA_DQ<25>
  43  VSS17  POWER  = GND
  44  DQS3_A_T  BI  = M_C_CPU0_SA_DQS_DP<3>
  45  DQS3_A_C  BI  = M_C_CPU0_SA_DQS_DN<3>
  46  VSS18  POWER  = GND
  47  DQ28_A  BI  = M_C_CPU0_SA_DQ<28>
  48  VSS19  POWER  = GND
  49  DQ29_A  BI  = M_C_CPU0_SA_DQ<29>
  50  VSS20  POWER  = GND
  51  CB0_A  BI  = M_C_CPU0_SA_CB<0>
  52  VSS21  POWER  = GND
  53  CB1_A  BI  = M_C_CPU0_SA_CB<1>
  54  VSS22  POWER  = GND
  55  DQS4_A_T  BI  = M_C_CPU0_SA_DQS_DP<4>
  56  DQS4_A_C  BI  = M_C_CPU0_SA_DQS_DN<4>
  57  VSS23  POWER  = GND
  58  CB4_A  BI  = M_C_CPU0_SA_CB<4>
  59  VSS24  POWER  = GND
  60  CB5_A  BI  = M_C_CPU0_SA_CB<5>
  61  VSS25  POWER  = GND
  62  ALERT_N  OUT  = M_C_CPU0_ALERT_N
  63  VSS26  POWER  = GND
  64  CS0_A_N  IN  = M_C_CPU0_SA_CS_N<2>
  65  VSS27  POWER  = GND
  66  CA0_A  IN  = M_C_CPU0_SA_CA<0>
  67  VSS28  POWER  = GND
  68  CA2_A  IN  = M_C_CPU0_SA_CA<2>
  69  VSS29  POWER  = GND
  70  CA4_A  IN  = M_C_CPU0_SA_CA<4>
  71  VSS30  POWER  = GND
  72  CA6_A  IN  = M_C_CPU0_SA_CA<6>
  73  VSS31  POWER  = GND
  74  PAR_A  IN  = M_C_CPU0_SA_PAR
  75  VSS32  POWER  = GND
  76  CA0_B  IN  = M_C_CPU0_SB_CA<0>
  77  VSS33  POWER  = GND
  78  CA2_B  IN  = M_C_CPU0_SB_CA<2>
  79  VSS34  POWER  = GND
  80  CA4_B  IN  = M_C_CPU0_SB_CA<4>
  81  VSS35  POWER  = GND
  82  CA6_B  IN  = M_C_CPU0_SB_CA<6>
  83  VSS36  POWER  = GND
  84  CS0_B_N  IN  = M_C_CPU0_SB_CS_N<2>
  85  VSS37  POWER  = GND
  86  \lbd||rsp_a_n\  OUT  = M_C_CPU0_SA_RSP<1>
  87  \lbs||rsp_b_n\  OUT  = M_C_CPU0_SB_RSP<1>
  88  VSS38  POWER  = GND
  89  CB4_B  BI  = M_C_CPU0_SB_CB<4>
  90  VSS39  POWER  = GND
  91  CB5_B  BI  = M_C_CPU0_SB_CB<5>
  92  VSS40  POWER  = GND
  93  \dqs9_b_t||tdqs9_b_t||dbi4_b_n\  BI  = M_C_CPU0_SB_DQS_DP<9>
  94  \dqs9_b_c||tdqs9_b_c\  BI  = M_C_CPU0_SB_DQS_DN<9>
  95  VSS41  POWER  = GND
  96  CB0_B  BI  = M_C_CPU0_SB_CB<0>
  97  VSS42  POWER  = GND
  98  CB1_B  BI  = M_C_CPU0_SB_CB<1>
  99  VSS43  POWER  = GND
  100  DQ0_B  BI  = M_C_CPU0_SB_DQ<0>
  101  VSS44  POWER  = GND
  102  DQ1_B  BI  = M_C_CPU0_SB_DQ<1>
  103  VSS45  POWER  = GND
  104  DQS0_B_T  BI  = M_C_CPU0_SB_DQS_DP<0>
  105  DQS0_B_C  BI  = M_C_CPU0_SB_DQS_DN<0>
  106  VSS46  POWER  = GND
  107  DQ4_B  BI  = M_C_CPU0_SB_DQ<4>
  108  VSS47  POWER  = GND
  109  DQ5_B  BI  = M_C_CPU0_SB_DQ<5>
  110  VSS48  POWER  = GND
  111  DQ8_B  BI  = M_C_CPU0_SB_DQ<8>
  112  VSS49  POWER  = GND
  113  DQ9_B  BI  = M_C_CPU0_SB_DQ<9>
  114  VSS50  POWER  = GND
  115  DQS1_B_T  BI  = M_C_CPU0_SB_DQS_DP<1>
  116  DQS1_B_C  BI  = M_C_CPU0_SB_DQS_DN<1>
  117  VSS51  POWER  = GND
  118  DQ12_B  BI  = M_C_CPU0_SB_DQ<12>
  119  VSS52  POWER  = GND
  120  DQ13_B  BI  = M_C_CPU0_SB_DQ<13>
  121  VSS53  POWER  = GND
  122  DQ16_B  BI  = M_C_CPU0_SB_DQ<16>
  123  VSS54  POWER  = GND
  124  DQ17_B  BI  = M_C_CPU0_SB_DQ<17>
  125  VSS55  POWER  = GND
  126  DQS2_B_T  BI  = M_C_CPU0_SB_DQS_DP<2>
  127  DQS2_B_C  BI  = M_C_CPU0_SB_DQS_DN<2>
  128  VSS56  POWER  = GND
  129  DQ20_B  BI  = M_C_CPU0_SB_DQ<20>
  130  VSS57  POWER  = GND
  131  DQ21_B  BI  = M_C_CPU0_SB_DQ<21>
  132  VSS58  POWER  = GND
  133  DQ24_B  BI  = M_C_CPU0_SB_DQ<24>
  134  VSS59  POWER  = GND
  135  DQ25_B  BI  = M_C_CPU0_SB_DQ<25>
  136  VSS60  POWER  = GND
  137  DQS3_B_T  BI  = M_C_CPU0_SB_DQS_DP<3>
  138  DQS3_B_C  BI  = M_C_CPU0_SB_DQS_DN<3>
  139  VSS61  POWER  = GND
  140  DQ28_B  BI  = M_C_CPU0_SB_DQ<28>
  141  VSS62  POWER  = GND
  142  DQ29_B  BI  = M_C_CPU0_SB_DQ<29>
  143  VSS63  POWER  = GND
  144  RFU1  TRI  = TP_CHC_CPU0_DIMM2_FRU_1
  145  VIN_BULK1  POWER  = P12V_S3_AUX_CPU0_NVDIMM
  146  VIN_BULK2  POWER  = P12V_S3_AUX_CPU0_NVDIMM
  147  \pwr_good||fail_n\  BI  = PWRGD_CHC_CPU0_DIMM2
  148  HSA  IN  = PD_CHC_CPU0_DIMM2_SAA
  149  RFU2  TRI  = TP_CHC_CPU0_DIMM2_FRU_2
  150  RFU3  TRI  = TP_CHC_CPU0_DIMM2_FRU_3
  151  VSS64  POWER  = GND
  152  DQ2_A  BI  = M_C_CPU0_SA_DQ<2>
  153  VSS65  POWER  = GND
  154  DQ3_A  BI  = M_C_CPU0_SA_DQ<3>
  155  VSS66  POWER  = GND
  156  \dqs5_a_c||tdqs5_a_c||dqs5_a_t||tdqs5_a_t\  BI  = M_C_CPU0_SA_DQS_DN<5>
  157  \dqs5_a_t||tdqs5_a_t\  BI  = M_C_CPU0_SA_DQS_DP<5>
  158  VSS67  POWER  = GND
  159  DQ6_A  BI  = M_C_CPU0_SA_DQ<6>
  160  VSS68  POWER  = GND
  161  DQ7_A  BI  = M_C_CPU0_SA_DQ<7>
  162  VSS69  POWER  = GND
  163  DQ10_A  BI  = M_C_CPU0_SA_DQ<10>
  164  VSS70  POWER  = GND
  165  DQ11_A  BI  = M_C_CPU0_SA_DQ<11>
  166  VSS71  POWER  = GND
  167  \dqs6_a_c||tdqs6_a_c||dqs6_a_t||tdqs6_a_t\  BI  = M_C_CPU0_SA_DQS_DN<6>
  168  \dqs6_a_t||tdqs6_a_t\  BI  = M_C_CPU0_SA_DQS_DP<6>
  169  VSS72  POWER  = GND
  170  DQ14_A  BI  = M_C_CPU0_SA_DQ<14>
  171  VSS73  POWER  = GND
  172  DQ15_A  BI  = M_C_CPU0_SA_DQ<15>
  173  VSS74  POWER  = GND
  174  DQ18_A  BI  = M_C_CPU0_SA_DQ<18>
  175  VSS75  POWER  = GND
  176  DQ19_A  BI  = M_C_CPU0_SA_DQ<19>
  177  VSS76  POWER  = GND
  178  \dqs7_a_c||tdqs7_a_c\  BI  = M_C_CPU0_SA_DQS_DN<7>
  179  \dqs7_a_t||tdqs7_a_t\  BI  = M_C_CPU0_SA_DQS_DP<7>
  180  VSS77  POWER  = GND
  181  DQ22_A  BI  = M_C_CPU0_SA_DQ<22>
  182  VSS78  POWER  = GND
  183  DQ23_A  BI  = M_C_CPU0_SA_DQ<23>
  184  VSS79  POWER  = GND
  185  DQ26_A  BI  = M_C_CPU0_SA_DQ<26>
  186  VSS80  POWER  = GND
  187  DQ27_A  BI  = M_C_CPU0_SA_DQ<27>
  188  VSS81  POWER  = GND
  189  \dqs8_a_c||tdqs8_a_c\  BI  = M_C_CPU0_SA_DQS_DN<8>
  190  \dqs8_a_t||tdqs8_a_t\  BI  = M_C_CPU0_SA_DQS_DP<8>
  191  VSS82  POWER  = GND
  192  DQ30_A  BI  = M_C_CPU0_SA_DQ<30>
  193  VSS83  POWER  = GND
  194  DQ31_A  BI  = M_C_CPU0_SA_DQ<31>
  195  VSS84  POWER  = GND
  196  CB2_A  BI  = M_C_CPU0_SA_CB<2>
  197  VSS85  POWER  = GND
  198  CB3_A  BI  = M_C_CPU0_SA_CB<3>
  199  VSS86  POWER  = GND
  200  \dqs9_a_c||tdqs9_a_c\  BI  = M_C_CPU0_SA_DQS_DN<9>
  201  \dqs9_a_t||tdqs9_a_t\  BI  = M_C_CPU0_SA_DQS_DP<9>
  202  VSS87  POWER  = GND
  203  CB6_A  BI  = M_C_CPU0_SA_CB<6>
  204  VSS88  POWER  = GND
  205  CB7_A  BI  = M_C_CPU0_SA_CB<7>
  206  VSS89  POWER  = GND
  207  RESET_N  IN  = RST_M_CD_CPU0_FPGA_N
  208  VSS90  POWER  = GND
  209  CS1_A_N  IN  = M_C_CPU0_SA_CS_N<3>
  210  VSS91  POWER  = GND
  211  CA1_A  IN  = M_C_CPU0_SA_CA<1>
  212  VSS92  POWER  = GND
  213  CA3_A  IN  = M_C_CPU0_SA_CA<3>
  214  VSS93  POWER  = GND
  215  CA5_A  IN  = M_C_CPU0_SA_CA<5>
  216  VSS94  POWER  = GND
  217  CK_T  IN  = M_C_CPU0_CLK_DP<1>
  218  CK_C  IN  = M_C_CPU0_CLK_DN<1>
  219  VSS95  POWER  = GND
  220  RFU4  TRI  = TP_CHC_CPU0_DIMM2_FRU_4
  221  CA1_B  IN  = M_C_CPU0_SB_CA<1>
  222  VSS96  POWER  = GND
  223  CA3_B  IN  = M_C_CPU0_SB_CA<3>
  224  VSS97  POWER  = GND
  225  CA5_B  IN  = M_C_CPU0_SB_CA<5>
  226  VSS98  POWER  = GND
  227  PAR_B  IN  = M_C_CPU0_SB_PAR
  228  VSS99  POWER  = GND
  229  CS1_B_N  IN  = M_C_CPU0_SB_CS_N<3>
  230  VSS100  POWER  = GND
  231  RFU5  TRI  = TP_CHC_CPU0_DIMM2_FRU_5
  232  RFU6  TRI  = TP_CHC_CPU0_DIMM2_FRU_6
  233  VSS101  POWER  = GND
  234  CB6_B  BI  = M_C_CPU0_SB_CB<6>
  235  VSS102  POWER  = GND
  236  CB7_B  BI  = M_C_CPU0_SB_CB<7>
  237  VSS103  POWER  = GND
  238  DQS4_B_C  BI  = M_C_CPU0_SB_DQS_DN<4>
  239  DQS4_B_T  BI  = M_C_CPU0_SB_DQS_DP<4>
  240  VSS104  POWER  = GND
  241  CB2_B  BI  = M_C_CPU0_SB_CB<2>
  242  VSS105  POWER  = GND
  243  CB3_B  BI  = M_C_CPU0_SB_CB<3>
  244  VSS106  POWER  = GND
  245  DQ2_B  BI  = M_C_CPU0_SB_DQ<2>
  246  VSS107  POWER  = GND
  247  DQ3_B  BI  = M_C_CPU0_SB_DQ<3>
  248  VSS108  POWER  = GND
  249  \dqs5_b_c||tdqs5_b_c\  BI  = M_C_CPU0_SB_DQS_DN<5>
  250  \dqs5_b_t||tdqs5_b_t\  BI  = M_C_CPU0_SB_DQS_DP<5>
  251  VSS109  POWER  = GND
  252  DQ6_B  BI  = M_C_CPU0_SB_DQ<6>
  253  VSS110  POWER  = GND
  254  DQ7_B  BI  = M_C_CPU0_SB_DQ<7>
  255  VSS111  POWER  = GND
  256  DQ10_B  BI  = M_C_CPU0_SB_DQ<10>
  257  VSS112  POWER  = GND
  258  DQ11_B  BI  = M_C_CPU0_SB_DQ<11>
  259  VSS113  POWER  = GND
  260  \dqs6_b_c||tdqs6_b_c\  BI  = M_C_CPU0_SB_DQS_DN<6>
  261  \dqs6_b_t||tdqs6_b_t\  BI  = M_C_CPU0_SB_DQS_DP<6>
  262  VSS114  POWER  = GND
  263  DQ14_B  BI  = M_C_CPU0_SB_DQ<14>
  264  VSS115  POWER  = GND
  265  DQ15_B  BI  = M_C_CPU0_SB_DQ<15>
  266  VSS116  POWER  = GND
  267  DQ18_B  BI  = M_C_CPU0_SB_DQ<18>
  268  VSS117  POWER  = GND
  269  DQ19_B  BI  = M_C_CPU0_SB_DQ<19>
  270  VSS118  POWER  = GND
  271  \dqs7_b_c||tdqs7_b_c\  BI  = M_C_CPU0_SB_DQS_DN<7>
  272  \dqs7_b_t||tdqs7_b_t\  BI  = M_C_CPU0_SB_DQS_DP<7>
  273  VSS119  POWER  = GND
  274  DQ22_B  BI  = M_C_CPU0_SB_DQ<22>
  275  VSS120  POWER  = GND
  276  DQ23_B  BI  = M_C_CPU0_SB_DQ<23>
  277  VSS121  POWER  = GND
  278  DQ26_B  BI  = M_C_CPU0_SB_DQ<26>
  279  VSS122  POWER  = GND
  280  DQ27_B  BI  = M_C_CPU0_SB_DQ<27>
  281  VSS123  POWER  = GND
  282  \dqs8_b_c||tdqs8_b_c\  BI  = M_C_CPU0_SB_DQS_DN<8>
  283  \dqs8_b_t||tdqs8_b_t\  BI  = M_C_CPU0_SB_DQS_DP<8>
  284  VSS124  POWER  = GND
  285  DQ30_B  BI  = M_C_CPU0_SB_DQ<30>
  286  VSS125  POWER  = GND
  287  DQ31_B  BI  = M_C_CPU0_SB_DQ<31>
  288  VSS126  POWER  = GND
  G1  G1  POWER  = GND
  G2  G2  POWER  = GND
  G3  G3  POWER  = GND
